# BASEBOARD_FAB2 (Tioga Pass) — schematic netlist excerpt (pin names and nets, part order shuffled) for the footprints in the layout excerpt that follows; sources: Cadence DE-HDL packaged netlist, KiCad conversion of Wiwynn_Tioga_Pass_MB.brd

EU4G1  NCP3232L  IC  pkg SM  page 233
  SS  = VR_PVPP_GHJ_SS
  FB  = VR_FB_PVPP_GHJ
  COMP  = VR_COMP_PVPP_GHJ_3
  ISET  = VR_PVPP_GHJ_ISET
  AGND  = AGND_PVPP_GHJ
  OTS  = AGND_PVPP_GHJ
  PG  = PWRGD_PVPP_GHJ_R
  VIN(0)  = VR_FET_SW_P12V_STBY_PVPP_GHJ
  VIN(1)  = VR_FET_SW_P12V_STBY_PVPP_GHJ
  VIN(2)  = VR_FET_SW_P12V_STBY_PVPP_GHJ
  VIN(3)  = VR_FET_SW_P12V_STBY_PVPP_GHJ
  VIN(4)  = VR_FET_SW_P12V_STBY_PVPP_GHJ
  VIN(5)  = VR_FET_SW_P12V_STBY_PVPP_GHJ
  VIN(6)  = VR_FET_SW_P12V_STBY_PVPP_GHJ
  VSWH(0)  = VR_PVPP_GHJ_PHASE
  PGND(0)  = GND
  PGND(1)  = GND
  PGND(2)  = GND
  PGND(3)  = GND
  PGND(4)  = GND
  PGND(5)  = GND
  PGND(6)  = GND
  PGND(7)  = GND
  PGND(8)  = GND
  PGND(9)  = GND
  PGND(10)  = GND
  PGND(11)  = GND
  PGND(12)  = GND
  VSWH(1)  = VR_PVPP_GHJ_PHASE
  VSWH(2)  = VR_PVPP_GHJ_PHASE
  VSWH(3)  = VR_PVPP_GHJ_PHASE
  VSWH(4)  = VR_PVPP_GHJ_PHASE
  VSWH(5)  = VR_PVPP_GHJ_PHASE
  VSWH(6)  = VR_PVPP_GHJ_PHASE
  VSW  = VR_PVPP_GHJ_PHASE
  BST  = VR_PVPP_GHJ_BOOT
  PGND(13)  = GND
  VB  = VR_VB_PVPP_GHJ
  VCC  = VR_FET_SW_P12V_STBY_PVPP_GHJ
  EN  = FM_PVPP_PVDDQ_CPU1_EN_GHJ
  GND  = GND
  VIN(7)  = VR_FET_SW_P12V_STBY_PVPP_GHJ
  VSWH(7)  = VR_PVPP_GHJ_PHASE

(kicad_pcb
	(version 20260206)
	(generator "pcbnew")
	(generator_version "10.0")
	(general
		(thickness 1.6)
		(legacy_teardrops no)
	)
	(paper "A4")
	(title_block
		(title "Wiwynn_Tioga_Pass_MB.brd")
		(comment 1 "Tioga Pass / footprint 1232 of 4770 (EU4G1), pads 36-43 of 43")
	)
	(layers
		(0 "F.Cu" signal "TOP")
		(4 "In1.Cu" signal "L2GND")
		(6 "In2.Cu" signal "L3")
		(8 "In3.Cu" signal "L4GND")
		(10 "In4.Cu" signal "L5")
		(12 "In5.Cu" signal "L6GND")
		(14 "In6.Cu" signal "L7VCC")
		(16 "In7.Cu" signal "L8VCC")
		(18 "In8.Cu" signal "L9GND")
		(20 "In9.Cu" signal "L10")
		(22 "In10.Cu" signal "L11GND")
		(24 "In11.Cu" signal "L12")
		(26 "In12.Cu" signal "L13GND")
		(2 "B.Cu" signal "BOTTOM")
		(9 "F.Adhes" user "F.Adhesive")
		(11 "B.Adhes" user "B.Adhesive")
		(13 "F.Paste" user "Package Geometry/Pastemask Top")
		(15 "B.Paste" user "Package Geometry/Pastemask Bottom")
		(5 "F.SilkS" user "Ref Des/Silkscreen Top")
		(7 "B.SilkS" user "Ref Des/Silkscreen Bottom")
		(1 "F.Mask" user "Board Geometry/Soldermask Top")
		(3 "B.Mask" user "Board Geometry/Soldermask Bottom")
		(17 "Dwgs.User" user "User.Drawings")
		(19 "Cmts.User" user "User.Comments")
		(21 "Eco1.User" user "User.Eco1")
		(23 "Eco2.User" user "User.Eco2")
		(25 "Edge.Cuts" user "Board Geometry/Outline")
		(27 "Margin" user)
		(31 "F.CrtYd" user "Package Geometry/Place Bound Top")
		(29 "B.CrtYd" user "Package Geometry/Place Bound Bottom")
		(35 "F.Fab" user "Ref Des/Assembly Top")
		(33 "B.Fab" user "Ref Des/Assembly Bottom")
	)
	(footprint ""
		(layer "F.Cu")
		(at 177.673 -13.335 90)
		(property "Reference" "EU4G1"
			(at 5.18033 -0.889 0)
			(unlocked yes)
			(layer "F.SilkS")
			(effects
				(font
					(size 0.7874 0.5842)
					(thickness 0.1524)
				)
				(justify left)
			)
		)
		(property "Value" ""
			(at 0 0 90)
			(layer "F.Fab")
			(effects
				(font
					(size 1.27 1.27)
				)
			)
		)
		(duplicate_pad_numbers_are_jumpers no)
		(pad "36" smd custom
			(at -0.249936 -2.8321 90)
			(size 0.06985 0.06985)
			(layers "F.Cu" "F.Mask" "F.Paste")
			(net "VR_PVPP_GHJ_BOOT")
			(options
				(clearance outline)
				(anchor circle)
			)
			(primitives
				(gr_poly
					(pts
						(arc
							(start 0.1397 0.2413)
							(mid 0 0.381)
							(end -0.1397 0.2413)
						)
						(xy -0.1397 -0.381) (xy 0.1397 -0.381)
					)
					(width 0)
					(fill yes)
				)
			)
		)
		(pad "37" smd custom
			(at -0.750062 -2.8321 90)
			(size 0.06985 0.06985)
			(layers "F.Cu" "F.Mask" "F.Paste")
			(net "GND")
			(options
				(clearance outline)
				(anchor circle)
			)
			(primitives
				(gr_poly
					(pts
						(arc
							(start 0.1397 0.2413)
							(mid 0 0.381)
							(end -0.1397 0.2413)
						)
						(xy -0.1397 -0.381) (xy 0.1397 -0.381)
					)
					(width 0)
					(fill yes)
				)
			)
		)
		(pad "38" smd custom
			(at -1.249934 -2.8321 90)
			(size 0.06985 0.06985)
			(layers "F.Cu" "F.Mask" "F.Paste")
			(net "VR_VB_PVPP_GHJ")
			(options
				(clearance outline)
				(anchor circle)
			)
			(primitives
				(gr_poly
					(pts
						(arc
							(start 0.1397 0.2413)
							(mid 0 0.381)
							(end -0.1397 0.2413)
						)
						(xy -0.1397 -0.381) (xy 0.1397 -0.381)
					)
					(width 0)
					(fill yes)
				)
			)
		)
		(pad "39" smd custom
			(at -1.75006 -2.8321 90)
			(size 0.06985 0.06985)
			(layers "F.Cu" "F.Mask" "F.Paste")
			(net "VR_FET_SW_P12V_STBY_PVPP_GHJ")
			(options
				(clearance outline)
				(anchor circle)
			)
			(primitives
				(gr_poly
					(pts
						(arc
							(start 0.1397 0.2413)
							(mid 0 0.381)
							(end -0.1397 0.2413)
						)
						(xy -0.1397 -0.381) (xy 0.1397 -0.381)
					)
					(width 0)
					(fill yes)
				)
			)
		)
		(pad "40" smd custom
			(at -2.249932 -2.8321 90)
			(size 0.06985 0.06985)
			(layers "F.Cu" "F.Mask" "F.Paste")
			(net "FM_PVPP_PVDDQ_CPU1_EN_GHJ")
			(options
				(clearance outline)
				(anchor circle)
			)
			(primitives
				(gr_poly
					(pts
						(arc
							(start 0.1397 0.2413)
							(mid 0 0.381)
							(end -0.1397 0.2413)
						)
						(xy -0.1397 -0.381) (xy 0.1397 -0.381)
					)
					(width 0)
					(fill yes)
				)
			)
		)
		(pad "41" smd rect
			(at -1.4478 -1.1938 90)
			(size 1.4986 2.0066)
			(layers "F.Cu" "F.Mask" "F.Paste")
			(net "GND")
		)
		(pad "42" smd rect
			(at -1.4478 1.1938 90)
			(size 1.4986 2.0066)
			(layers "F.Cu" "F.Mask" "F.Paste")
			(net "VR_FET_SW_P12V_STBY_PVPP_GHJ")
		)
		(pad "43" smd rect
			(at 1.0033 0 90)
			(size 2.3876 4.3942)
			(layers "F.Cu" "F.Mask" "F.Paste")
			(net "VR_PVPP_GHJ_PHASE")
		)
	)
)
